(kicad_pcb
	(version 20241229)
	(generator "pcbnew")
	(generator_version "9.0")
	(general
		(thickness 1.62)
		(legacy_teardrops no)
	)
	(paper "A4")
	(title_block
		(title "OCuLink to 10GbE adapter")
		(date "2026-02-23")
		(rev "1.1.0")
		(company "Antmicro Ltd")
		(comment 1 "www.antmicro.com")
		(comment 9 "footprints 243-248 of 510")
	)
	(layers
		(0 "F.Cu" signal)
		(4 "In1.Cu" signal)
		(6 "In2.Cu" signal)
		(8 "In3.Cu" signal)
		(10 "In4.Cu" signal)
		(12 "In5.Cu" signal)
		(14 "In6.Cu" signal)
		(2 "B.Cu" signal)
		(9 "F.Adhes" user "F.Adhesive")
		(11 "B.Adhes" user "B.Adhesive")
		(13 "F.Paste" user)
		(15 "B.Paste" user)
		(5 "F.SilkS" user "F.Silkscreen")
		(7 "B.SilkS" user "B.Silkscreen")
		(1 "F.Mask" user)
		(3 "B.Mask" user)
		(17 "Dwgs.User" user "User.Drawings")
		(19 "Cmts.User" user "User.Comments")
		(21 "Eco1.User" user "User.Eco1")
		(23 "Eco2.User" user "User.Eco2")
		(25 "Edge.Cuts" user)
		(27 "Margin" user)
		(31 "F.CrtYd" user "F.Courtyard")
		(29 "B.CrtYd" user "B.Courtyard")
		(35 "F.Fab" user)
		(33 "B.Fab" user)
	)
	(footprint "antmicro-footprints:R_0402_1005Metric"
		(layer "F.Cu")
		(at 110.15 100.1 -90)
		(descr "Resistor SMD 0402")
		(tags "resistor SMD 0402")
		(property "Reference" "R175"
			(at -0.8 -1.45 90)
			(layer "F.SilkS")
			(effects
				(font
					(size 0.7 0.7)
					(thickness 0.15)
				)
				(justify left bottom)
			)
		)
		(property "Value" "R_10k_0402"
			(at -1.011843 1.772046 90)
			(layer "F.Fab")
			(hide yes)
			(effects
				(font
					(size 0.7 0.7)
					(thickness 0.15)
				)
				(justify right top)
			)
		)
		(property "Datasheet" "https://www.bourns.com/docs/product-datasheets/cr.pdf"
			(at 0 0 90)
			(layer "F.Fab")
			(hide yes)
			(effects
				(font
					(size 1.27 1.27)
					(thickness 0.15)
				)
			)
		)
		(property "Description" "SMD Chip Resistor, 10 kohm, ± 1%, 62.5 mW, 0402 [1005 Metric], Thick Film, General Purpose"
			(at 0 0 90)
			(layer "F.Fab")
			(hide yes)
			(effects
				(font
					(size 1.27 1.27)
					(thickness 0.15)
				)
			)
		)
		(property "MPN" "CR0402-FX-1002GLF"
			(at 0 0 270)
			(unlocked yes)
			(layer "F.Fab")
			(hide yes)
			(effects
				(font
					(size 1 1)
					(thickness 0.15)
				)
			)
		)
		(property "Manufacturer" "Bourns"
			(at 0 0 270)
			(unlocked yes)
			(layer "F.Fab")
			(hide yes)
			(effects
				(font
					(size 1 1)
					(thickness 0.15)
				)
			)
		)
		(property "License" "Apache-2.0"
			(at 0 0 270)
			(unlocked yes)
			(layer "F.Fab")
			(hide yes)
			(effects
				(font
					(size 1 1)
					(thickness 0.15)
				)
			)
		)
		(property "Author" "Antmicro"
			(at 0 0 270)
			(unlocked yes)
			(layer "F.Fab")
			(hide yes)
			(effects
				(font
					(size 1 1)
					(thickness 0.15)
				)
			)
		)
		(property "Val" "10k"
			(at 0 0 270)
			(unlocked yes)
			(layer "F.Fab")
			(hide yes)
			(effects
				(font
					(size 1 1)
					(thickness 0.15)
				)
			)
		)
		(property "Tolerance" "1%"
			(at 0 0 270)
			(unlocked yes)
			(layer "F.Fab")
			(hide yes)
			(effects
				(font
					(size 1 1)
					(thickness 0.15)
				)
			)
		)
		(sheetname "/Fan controller/")
		(sheetfile "fan-controller.kicad_sch")
		(attr smd exclude_from_pos_files exclude_from_bom dnp)
		(fp_rect
			(start -0.925 -0.47)
			(end 0.925 0.47)
			(stroke
				(width 0.05)
				(type default)
			)
			(fill no)
			(layer "F.CrtYd")
		)
		(fp_rect
			(start -0.5 -0.25)
			(end 0.5 0.25)
			(stroke
				(width 0.15)
				(type solid)
			)
			(fill no)
			(layer "F.Fab")
		)
		(pad "1" smd roundrect
			(at -0.48 0 270)
			(size 0.59 0.64)
			(layers "F.Cu" "F.Mask" "F.Paste")
			(roundrect_rratio 0.25)
			(net 397 "Net-(R175-Pad1)")
			(pintype "passive")
		)
		(pad "2" smd roundrect
			(at 0.48 0 270)
			(size 0.59 0.64)
			(layers "F.Cu" "F.Mask" "F.Paste")
			(roundrect_rratio 0.25)
			(net 385 "/Fan controller/SENSE")
			(pintype "passive")
		)
	)
	(footprint "antmicro-footprints:C_0603_1608Metric_EIA"
		(layer "F.Cu")
		(at 77.2 86.35 180)
		(descr "Capacitor SMD 0603, IPC-7351 Density Level A")
		(tags "Capacitor 0603")
		(property "Reference" "C151"
			(at -1.4 8.144 0)
			(layer "F.SilkS")
			(effects
				(font
					(size 0.7 0.7)
					(thickness 0.15)
				)
				(justify right top)
			)
		)
		(property "Value" "C_22u_16V_0603"
			(at -1.42757 1.770288 0)
			(layer "F.Fab")
			(hide yes)
			(effects
				(font
					(size 0.7 0.7)
					(thickness 0.15)
				)
				(justify right top)
			)
		)
		(property "Datasheet" "https://product.samsungsem.com/mlcc/CL10A226MO7JZN.do"
			(at 0 0 0)
			(layer "F.Fab")
			(hide yes)
			(effects
				(font
					(size 1.27 1.27)
					(thickness 0.15)
				)
			)
		)
		(property "Description" "SMD Multilayer Ceramic Capacitor"
			(at 0 0 0)
			(layer "F.Fab")
			(hide yes)
			(effects
				(font
					(size 1.27 1.27)
					(thickness 0.15)
				)
			)
		)
		(property "MPN" "CL10A226MO7JZNC"
			(at 0 0 180)
			(unlocked yes)
			(layer "F.Fab")
			(hide yes)
			(effects
				(font
					(size 1 1)
					(thickness 0.15)
				)
			)
		)
		(property "Manufacturer" "Samsung Electro-Mechanics"
			(at 0 0 180)
			(unlocked yes)
			(layer "F.Fab")
			(hide yes)
			(effects
				(font
					(size 1 1)
					(thickness 0.15)
				)
			)
		)
		(property "License" "Apache-2.0"
			(at 0 0 180)
			(unlocked yes)
			(layer "F.Fab")
			(hide yes)
			(effects
				(font
					(size 1 1)
					(thickness 0.15)
				)
			)
		)
		(property "Author" "Antmicro"
			(at 0 0 180)
			(unlocked yes)
			(layer "F.Fab")
			(hide yes)
			(effects
				(font
					(size 1 1)
					(thickness 0.15)
				)
			)
		)
		(property "Val" "22u"
			(at 0 0 180)
			(unlocked yes)
			(layer "F.Fab")
			(hide yes)
			(effects
				(font
					(size 1 1)
					(thickness 0.15)
				)
			)
		)
		(property "Voltage" "16V"
			(at 0 0 180)
			(unlocked yes)
			(layer "F.Fab")
			(hide yes)
			(effects
				(font
					(size 1 1)
					(thickness 0.15)
				)
			)
		)
		(property "Dielectric" ""
			(at 0 0 180)
			(unlocked yes)
			(layer "F.Fab")
			(hide yes)
			(effects
				(font
					(size 1 1)
					(thickness 0.15)
				)
			)
		)
		(sheetname "/X710-AT2 power/")
		(sheetfile "x710-at2-power.kicad_sch")
		(attr smd)
		(fp_line
			(start -0.15 0.55)
			(end 0.15 0.55)
			(stroke
				(width 0.15)
				(type solid)
			)
			(layer "F.SilkS")
		)
		(fp_line
			(start -0.15 -0.55)
			(end 0.15 -0.55)
			(stroke
				(width 0.15)
				(type solid)
			)
			(layer "F.SilkS")
		)
		(fp_rect
			(start -1.25 -0.65)
			(end 1.25 0.65)
			(stroke
				(width 0.05)
				(type solid)
			)
			(fill no)
			(layer "F.CrtYd")
		)
		(fp_rect
			(start -0.8 -0.45)
			(end 0.8 0.45)
			(stroke
				(width 0.15)
				(type solid)
			)
			(fill no)
			(layer "F.Fab")
		)
		(pad "1" smd roundrect
			(at -0.7 0 180)
			(size 0.8 1.1)
			(layers "F.Cu" "F.Mask" "F.Paste")
			(roundrect_rratio 0.2)
			(net 28 "GND")
			(pintype "passive")
		)
		(pad "2" smd roundrect
			(at 0.7 0 180)
			(size 0.8 1.1)
			(layers "F.Cu" "F.Mask" "F.Paste")
			(roundrect_rratio 0.2)
			(net 7 "+3V3")
			(pintype "passive")
		)
	)
	(footprint "antmicro-footprints:R_0402_1005Metric"
		(layer "F.Cu")
		(at 82.25 82.15 180)
		(descr "Resistor SMD 0402")
		(tags "resistor SMD 0402")
		(property "Reference" "R172"
			(at -0.8 -0.35 0)
			(layer "F.SilkS")
			(effects
				(font
					(size 0.7 0.7)
					(thickness 0.15)
				)
				(justify left bottom)
			)
		)
		(property "Value" "R_0R_0402"
			(at -1.011843 1.772046 0)
			(layer "F.Fab")
			(hide yes)
			(effects
				(font
					(size 0.7 0.7)
					(thickness 0.15)
				)
				(justify right top)
			)
		)
		(property "Datasheet" "https://industrial.panasonic.com/cdbs/www-data/pdf/RDA0000/AOA0000C301.pdf"
			(at 0 0 0)
			(layer "F.Fab")
			(hide yes)
			(effects
				(font
					(size 1.27 1.27)
					(thickness 0.15)
				)
			)
		)
		(property "Description" "SMD Chip Resistor, Jumper, 0 ohm, 100 mW, 0402 [1005 Metric], Thick Film, General Purpose"
			(at 0 0 0)
			(layer "F.Fab")
			(hide yes)
			(effects
				(font
					(size 1.27 1.27)
					(thickness 0.15)
				)
			)
		)
		(property "MPN" "ERJ2GE0R00X"
			(at 0 0 180)
			(unlocked yes)
			(layer "F.Fab")
			(hide yes)
			(effects
				(font
					(size 1 1)
					(thickness 0.15)
				)
			)
		)
		(property "Manufacturer" "Panasonic"
			(at 0 0 180)
			(unlocked yes)
			(layer "F.Fab")
			(hide yes)
			(effects
				(font
					(size 1 1)
					(thickness 0.15)
				)
			)
		)
		(property "License" "Apache-2.0"
			(at 0 0 180)
			(unlocked yes)
			(layer "F.Fab")
			(hide yes)
			(effects
				(font
					(size 1 1)
					(thickness 0.15)
				)
			)
		)
		(property "Author" "Antmicro"
			(at 0 0 180)
			(unlocked yes)
			(layer "F.Fab")
			(hide yes)
			(effects
				(font
					(size 1 1)
					(thickness 0.15)
				)
			)
		)
		(property "Val" "0R"
			(at 0 0 180)
			(unlocked yes)
			(layer "F.Fab")
			(hide yes)
			(effects
				(font
					(size 1 1)
					(thickness 0.15)
				)
			)
		)
		(property "Tolerance" "~"
			(at 0 0 180)
			(unlocked yes)
			(layer "F.Fab")
			(hide yes)
			(effects
				(font
					(size 1 1)
					(thickness 0.15)
				)
			)
		)
		(property "Current" "1A"
			(at 0 0 180)
			(unlocked yes)
			(layer "F.Fab")
			(hide yes)
			(effects
				(font
					(size 1 1)
					(thickness 0.15)
				)
			)
		)
		(sheetname "/X710-AT2 Misc/")
		(sheetfile "x710-at2-mics.kicad_sch")
		(attr smd exclude_from_pos_files exclude_from_bom dnp)
		(fp_rect
			(start -0.925 -0.47)
			(end 0.925 0.47)
			(stroke
				(width 0.05)
				(type default)
			)
			(fill no)
			(layer "F.CrtYd")
		)
		(fp_rect
			(start -0.5 -0.25)
			(end 0.5 0.25)
			(stroke
				(width 0.15)
				(type solid)
			)
			(fill no)
			(layer "F.Fab")
		)
		(pad "1" smd roundrect
			(at -0.48 0 180)
			(size 0.59 0.64)
			(layers "F.Cu" "F.Mask" "F.Paste")
			(roundrect_rratio 0.25)
			(net 78 "Net-(U10-VCC)")
			(pintype "passive")
		)
		(pad "2" smd roundrect
			(at 0.48 0 180)
			(size 0.59 0.64)
			(layers "F.Cu" "F.Mask" "F.Paste")
			(roundrect_rratio 0.25)
			(net 90 "+3V3_AUX")
			(pintype "passive")
		)
	)
	(footprint "antmicro-footprints:R_0402_1005Metric"
		(layer "F.Cu")
		(at 54.099999 108.249997 -90)
		(descr "Resistor SMD 0402")
		(tags "resistor SMD 0402")
		(property "Reference" "R26"
			(at -1.069997 3.019999 90)
			(layer "F.SilkS")
			(effects
				(font
					(size 0.7 0.7)
					(thickness 0.15)
				)
				(justify right top)
			)
		)
		(property "Value" "R_30k_0402"
			(at -1.011843 1.772046 90)
			(layer "F.Fab")
			(hide yes)
			(effects
				(font
					(size 0.7 0.7)
					(thickness 0.15)
				)
				(justify right top)
			)
		)
		(property "Datasheet" "https://www.bourns.com/docs/product-datasheets/cr.pdf"
			(at 0 0 90)
			(layer "F.Fab")
			(hide yes)
			(effects
				(font
					(size 1.27 1.27)
					(thickness 0.15)
				)
			)
		)
		(property "Description" "SMD Chip Resistor, 30 kohm, ± 1%, 63 mW, 0402 [1005 Metric], Thick Film, General Purpose"
			(at 0 0 90)
			(layer "F.Fab")
			(hide yes)
			(effects
				(font
					(size 1.27 1.27)
					(thickness 0.15)
				)
			)
		)
		(property "MPN" "CR0402-FX-3002GLF"
			(at 0 0 270)
			(unlocked yes)
			(layer "F.Fab")
			(hide yes)
			(effects
				(font
					(size 1 1)
					(thickness 0.15)
				)
			)
		)
		(property "Manufacturer" "Bourns"
			(at 0 0 270)
			(unlocked yes)
			(layer "F.Fab")
			(hide yes)
			(effects
				(font
					(size 1 1)
					(thickness 0.15)
				)
			)
		)
		(property "License" "Apache-2.0"
			(at 0 0 270)
			(unlocked yes)
			(layer "F.Fab")
			(hide yes)
			(effects
				(font
					(size 1 1)
					(thickness 0.15)
				)
			)
		)
		(property "Author" "Antmicro"
			(at 0 0 270)
			(unlocked yes)
			(layer "F.Fab")
			(hide yes)
			(effects
				(font
					(size 1 1)
					(thickness 0.15)
				)
			)
		)
		(property "Val" "30k"
			(at 0 0 270)
			(unlocked yes)
			(layer "F.Fab")
			(hide yes)
			(effects
				(font
					(size 1 1)
					(thickness 0.15)
				)
			)
		)
		(property "Tolerance" "1%"
			(at 0 0 270)
			(unlocked yes)
			(layer "F.Fab")
			(hide yes)
			(effects
				(font
					(size 1 1)
					(thickness 0.15)
				)
			)
		)
		(sheetname "/Power/")
		(sheetfile "power.kicad_sch")
		(attr smd)
		(fp_rect
			(start -0.925 -0.47)
			(end 0.925 0.47)
			(stroke
				(width 0.05)
				(type default)
			)
			(fill no)
			(layer "F.CrtYd")
		)
		(fp_rect
			(start -0.5 -0.25)
			(end 0.5 0.25)
			(stroke
				(width 0.15)
				(type solid)
			)
			(fill no)
			(layer "F.Fab")
		)
		(pad "1" smd roundrect
			(at -0.48 0 270)
			(size 0.59 0.64)
			(layers "F.Cu" "F.Mask" "F.Paste")
			(roundrect_rratio 0.25)
			(net 28 "GND")
			(pintype "passive")
		)
		(pad "2" smd roundrect
			(at 0.48 0 270)
			(size 0.59 0.64)
			(layers "F.Cu" "F.Mask" "F.Paste")
			(roundrect_rratio 0.25)
			(net 332 "/Power/1V0_FB")
			(pintype "passive")
		)
	)
	(footprint "antmicro-footprints:R_0402_1005Metric"
		(layer "F.Cu")
		(at 53.5 78 -90)
		(descr "Resistor SMD 0402")
		(tags "resistor SMD 0402")
		(property "Reference" "R170"
			(at -3.6 -0.02 90)
			(layer "F.SilkS")
			(effects
				(font
					(size 0.7 0.7)
					(thickness 0.15)
				)
				(justify right top)
			)
		)
		(property "Value" "R_1k_0402"
			(at -1.011843 1.772046 90)
			(layer "F.Fab")
			(hide yes)
			(effects
				(font
					(size 0.7 0.7)
					(thickness 0.15)
				)
				(justify right top)
			)
		)
		(property "Datasheet" "https://www.bourns.com/docs/product-datasheets/cr.pdf"
			(at 0 0 90)
			(layer "F.Fab")
			(hide yes)
			(effects
				(font
					(size 1.27 1.27)
					(thickness 0.15)
				)
			)
		)
		(property "Description" "SMD Chip Resistor, 1 kohm, ± 1%, 63 mW, 0402 [1005 Metric], Thick Film, General Purpose"
			(at 0 0 90)
			(layer "F.Fab")
			(hide yes)
			(effects
				(font
					(size 1.27 1.27)
					(thickness 0.15)
				)
			)
		)
		(property "MPN" "CR0402-FX-1001GLF"
			(at 0 0 270)
			(unlocked yes)
			(layer "F.Fab")
			(hide yes)
			(effects
				(font
					(size 1 1)
					(thickness 0.15)
				)
			)
		)
		(property "Manufacturer" "Bourns"
			(at 0 0 270)
			(unlocked yes)
			(layer "F.Fab")
			(hide yes)
			(effects
				(font
					(size 1 1)
					(thickness 0.15)
				)
			)
		)
		(property "License" "Apache-2.0"
			(at 0 0 270)
			(unlocked yes)
			(layer "F.Fab")
			(hide yes)
			(effects
				(font
					(size 1 1)
					(thickness 0.15)
				)
			)
		)
		(property "Author" "Antmicro"
			(at 0 0 270)
			(unlocked yes)
			(layer "F.Fab")
			(hide yes)
			(effects
				(font
					(size 1 1)
					(thickness 0.15)
				)
			)
		)
		(property "Val" "1k"
			(at 0 0 270)
			(unlocked yes)
			(layer "F.Fab")
			(hide yes)
			(effects
				(font
					(size 1 1)
					(thickness 0.15)
				)
			)
		)
		(property "Tolerance" "1%"
			(at 0 0 270)
			(unlocked yes)
			(layer "F.Fab")
			(hide yes)
			(effects
				(font
					(size 1 1)
					(thickness 0.15)
				)
			)
		)
		(sheetname "/Power/")
		(sheetfile "power.kicad_sch")
		(attr smd)
		(fp_rect
			(start -0.925 -0.47)
			(end 0.925 0.47)
			(stroke
				(width 0.05)
				(type default)
			)
			(fill no)
			(layer "F.CrtYd")
		)
		(fp_rect
			(start -0.5 -0.25)
			(end 0.5 0.25)
			(stroke
				(width 0.15)
				(type solid)
			)
			(fill no)
			(layer "F.Fab")
		)
		(pad "1" smd roundrect
			(at -0.48 0 270)
			(size 0.59 0.64)
			(layers "F.Cu" "F.Mask" "F.Paste")
			(roundrect_rratio 0.25)
			(net 79 "Net-(D11-A)")
			(pintype "passive")
		)
		(pad "2" smd roundrect
			(at 0.48 0 270)
			(size 0.59 0.64)
			(layers "F.Cu" "F.Mask" "F.Paste")
			(roundrect_rratio 0.25)
			(net 7 "+3V3")
			(pintype "passive")
		)
	)
	(footprint "antmicro-footprints:R_0402_1005Metric"
		(layer "F.Cu")
		(at 63.793 62.02)
		(descr "Resistor SMD 0402")
		(tags "resistor SMD 0402")
		(property "Reference" "R13"
			(at -1.023 -0.55 0)
			(layer "F.SilkS")
			(effects
				(font
					(size 0.7 0.7)
					(thickness 0.15)
				)
				(justify left bottom)
			)
		)
		(property "Value" "R_10k_0402"
			(at -1.011843 1.772046 0)
			(layer "F.Fab")
			(hide yes)
			(effects
				(font
					(size 0.7 0.7)
					(thickness 0.15)
				)
				(justify left bottom)
			)
		)
		(property "Datasheet" "https://www.bourns.com/docs/product-datasheets/cr.pdf"
			(at 0 0 0)
			(layer "F.Fab")
			(hide yes)
			(effects
				(font
					(size 1.27 1.27)
					(thickness 0.15)
				)
			)
		)
		(property "Description" "SMD Chip Resistor, 10 kohm, ± 1%, 62.5 mW, 0402 [1005 Metric], Thick Film, General Purpose"
			(at 0 0 0)
			(layer "F.Fab")
			(hide yes)
			(effects
				(font
					(size 1.27 1.27)
					(thickness 0.15)
				)
			)
		)
		(property "MPN" "CR0402-FX-1002GLF"
			(at 0 0 0)
			(unlocked yes)
			(layer "F.Fab")
			(hide yes)
			(effects
				(font
					(size 1 1)
					(thickness 0.15)
				)
			)
		)
		(property "Manufacturer" "Bourns"
			(at 0 0 0)
			(unlocked yes)
			(layer "F.Fab")
			(hide yes)
			(effects
				(font
					(size 1 1)
					(thickness 0.15)
				)
			)
		)
		(property "License" "Apache-2.0"
			(at 0 0 0)
			(unlocked yes)
			(layer "F.Fab")
			(hide yes)
			(effects
				(font
					(size 1 1)
					(thickness 0.15)
				)
			)
		)
		(property "Author" "Antmicro"
			(at 0 0 0)
			(unlocked yes)
			(layer "F.Fab")
			(hide yes)
			(effects
				(font
					(size 1 1)
					(thickness 0.15)
				)
			)
		)
		(property "Val" "10k"
			(at 0 0 0)
			(unlocked yes)
			(layer "F.Fab")
			(hide yes)
			(effects
				(font
					(size 1 1)
					(thickness 0.15)
				)
			)
		)
		(property "Tolerance" "1%"
			(at 0 0 0)
			(unlocked yes)
			(layer "F.Fab")
			(hide yes)
			(effects
				(font
					(size 1 1)
					(thickness 0.15)
				)
			)
		)
		(sheetname "/Power/")
		(sheetfile "power.kicad_sch")
		(attr smd)
		(fp_rect
			(start -0.925 -0.47)
			(end 0.925 0.47)
			(stroke
				(width 0.05)
				(type default)
			)
			(fill no)
			(layer "F.CrtYd")
		)
		(fp_rect
			(start -0.5 -0.25)
			(end 0.5 0.25)
			(stroke
				(width 0.15)
				(type solid)
			)
			(fill no)
			(layer "F.Fab")
		)
		(pad "1" smd roundrect
			(at -0.48 0)
			(size 0.59 0.64)
			(layers "F.Cu" "F.Mask" "F.Paste")
			(roundrect_rratio 0.25)
			(net 70 "Net-(D2-A)")
			(pintype "passive")
		)
		(pad "2" smd roundrect
			(at 0.48 0)
			(size 0.59 0.64)
			(layers "F.Cu" "F.Mask" "F.Paste")
			(roundrect_rratio 0.25)
			(net 350 "/Power/+12V_IN")
			(pintype "passive")
		)
	)
)
